# T6G (Grand Teton) — schematic netlist excerpt (pin names and nets, part order shuffled) for the footprints in the layout excerpt that follows; sources: Cadence DE-HDL packaged netlist, KiCad conversion of 04192023_DAF0TMB3IC0_F0TG_MB_C_brd_V02_OCP.brd

U6001  CYUSB330468LTXI  CYUSB3304-68LTXI IC  pkg QFN68_TH_0-4_8X8  page 176
  DVDD12_1  = P1V2_CPU0_USB_DVDD12
  RREF_USB2  = USB_CPU0_HUB1_RREF_USB2
  DVDD12_2  = P1V2_CPU0_USB_DVDD12
  AVDD33_1  = P3V3_AUX_CPU0_USB_AVDD33
  US_TXM  = USB3_CPU0_BMC_RX_HUB1_DN
  US_TXP  = USB3_CPU0_BMC_RX_HUB1_DP
  DVDD12_5  = P1V2_AUX
  US_RXM  = USB3_CPU0_BMC_TX_C1_DN
  US_RXP  = USB3_CPU0_BMC_TX_C1_DP
  AVDD12_1  = P1V2_AUX
  DS4_TXP  = NC
  DS4_TXM  = NC
  DVDD12_6  = P1V2_AUX
  DS4_RXM  = NC
  DS4_RXP  = NC
  AVDD12_2  = P1V2_AUX
  VBUS_US  = USB_CPU0_HUB1_VBUS_US
  VBUS_DS  = USB_CPU0_HUB1_VBUS_DS
  VDD_EFUSE  = P1V2_CPU0_USB_DVDD12
  SUSPEND  = TP_CPU0_USB_HUB1_SUSPEND
  RESERVED1  = PU_CPU0_USB_HUB_RESERVED1
  RESERVED2  = PU_CPU0_USB_HUB_RESERVED2
  MODE_SEL0  = USB_CPU0_HUB1_MODE_SEL0
  MODE_SEL1  = USB_CPU0_HUB1_MODE_SEL1
  NC_25  = NC
  RREF_SS  = USB_CPU0_HUB1_RREF_SS
  DVDD12_3  = P1V2_CPU0_USB_DVDD12
  VDD_IO  = P3V3_AUX
  PWR_EN  = PU_CPU0_USB_HUB_PWR_EN
  OVRCURR  = PU_CPU0_USB_HUB_OVRCURR
  \reset#\  = RST_USB_CPU0_HUB1_R_N
  I2C_CLK  = SMB_USB_CPU0_HUB1_SCL
  I2C_DATA  = SMB_USB_CPU0_HUB1_SDA
  AVDD12_3  = P1V2_AUX
  DS3_RXP  = NC
  DS3_RXM  = NC
  DVDD12_7  = P1V2_AUX
  DS3_TXP  = NC
  DS3_TXM  = NC
  GND  = GND
  DS2_TXP  = NC
  DS2_TXM  = NC
  DVDD12_8  = P1V2_AUX
  DS2_RXM  = NC
  DS2_RXP  = NC
  AVDD12_4  = P1V2_AUX
  DS1_TXP  = USB3_CPU0_BMC_HUB1_TX_DP
  DS1_TXM  = USB3_CPU0_BMC_HUB1_TX_DN
  DVDD12_4  = P1V2_AUX
  DS1_RXM  = USB3_CPU0_BMC_RX_C1_DN
  DS1_RXP  = USB3_CPU0_BMC_RX_C1_DP
  AVDD12_5  = P1V2_AUX
  AVDD12_6  = P1V2_AUX
  XTL_OUT  = XTAL_USB_CPU0_HUB1_XOUT
  XTL_IN  = XTAL_USB_CPU0_HUB1_XIN
  AVDD33_2  = P3V3_AUX
  US_DP  = USB2_CPU0_P0_R1_DP
  US_DM  = USB2_CPU0_P0_R1_DN
  DS1_DM  = USB2_CPU0_P0_HUB1_R_DN
  DS1_DP  = USB2_CPU0_P0_HUB1_R_DP
  AVDD33_3  = P3V3_AUX
  DS2_DP  = NC
  DS2_DM  = NC
  DS3_DM  = NC
  DS3_DP  = NC
  AVDD33_4  = P3V3_AUX
  DS4_DP  = NC
  DS4_DM  = NC
  EPAD  = GND

(kicad_pcb
	(version 20260206)
	(generator "pcbnew")
	(generator_version "10.0")
	(general
		(thickness 1.6)
		(legacy_teardrops no)
	)
	(paper "A4")
	(title_block
		(title "04192023_DAF0TMB3IC0_F0TG_MB_C_brd_V02_OCP.brd")
		(comment 1 "Grand Teton / footprint 3444 of 8354 (U6001), pads 1-45 of 69")
	)
	(layers
		(0 "F.Cu" signal "TOP")
		(4 "In1.Cu" signal "GND")
		(6 "In2.Cu" signal "IN1")
		(8 "In3.Cu" signal "GND1")
		(10 "In4.Cu" signal "IN2")
		(12 "In5.Cu" signal "GND2")
		(14 "In6.Cu" signal "IN3")
		(16 "In7.Cu" signal "GND3")
		(18 "In8.Cu" signal "VCC")
		(20 "In9.Cu" signal "VCC1")
		(22 "In10.Cu" signal "GND4")
		(24 "In11.Cu" signal "IN4")
		(26 "In12.Cu" signal "GND5")
		(28 "In13.Cu" signal "IN5")
		(30 "In14.Cu" signal "GND6")
		(32 "In15.Cu" signal "IN6")
		(34 "In16.Cu" signal "GND7")
		(2 "B.Cu" signal "BOTTOM")
		(9 "F.Adhes" user "F.Adhesive")
		(11 "B.Adhes" user "B.Adhesive")
		(13 "F.Paste" user "Package Geometry/Pastemask Top")
		(15 "B.Paste" user "Package Geometry/Pastemask Bottom")
		(5 "F.SilkS" user "Ref Des/Silkscreen Top")
		(7 "B.SilkS" user "Ref Des/Silkscreen Bottom")
		(1 "F.Mask" user "Board Geometry/Soldermask Top")
		(3 "B.Mask" user "Board Geometry/Soldermask Bottom")
		(17 "Dwgs.User" user "User.Drawings")
		(19 "Cmts.User" user "User.Comments")
		(21 "Eco1.User" user "User.Eco1")
		(23 "Eco2.User" user "User.Eco2")
		(25 "Edge.Cuts" user "Board Geometry/Outline")
		(27 "Margin" user)
		(31 "F.CrtYd" user "Package Geometry/Place Bound Top")
		(29 "B.CrtYd" user "Package Geometry/Place Bound Bottom")
		(35 "F.Fab" user "Ref Des/Assembly Top")
		(33 "B.Fab" user "Ref Des/Assembly Bottom")
	)
	(footprint ""
		(layer "F.Cu")
		(at 132.694172 -36.873434 180)
		(property "Reference" "U6001"
			(at -4.192016 6.04266 0)
			(unlocked yes)
			(layer "F.SilkS")
			(effects
				(font
					(size 0.7874 0.5842)
					(thickness 0.1524)
				)
				(justify left)
			)
		)
		(property "Value" ""
			(at 0 0 180)
			(layer "F.Fab")
			(effects
				(font
					(size 1.27 1.27)
				)
			)
		)
		(duplicate_pad_numbers_are_jumpers no)
		(pad "1" smd rect
			(at -3.999992 -3.199892 270)
			(size 0.1778 1.016)
			(layers "F.Cu" "F.Mask" "F.Paste")
			(net "P1V2_CPU0_USB_DVDD12")
		)
		(pad "2" smd rect
			(at -3.849878 -2.800096 270)
			(size 0.1778 1.3208)
			(layers "F.Cu" "F.Mask" "F.Paste")
			(net "USB_CPU0_HUB1_RREF_USB2")
		)
		(pad "3" smd rect
			(at -3.849878 -2.400046 270)
			(size 0.1778 1.3208)
			(layers "F.Cu" "F.Mask" "F.Paste")
			(net "P1V2_CPU0_USB_DVDD12")
		)
		(pad "4" smd rect
			(at -3.849878 -1.999996 270)
			(size 0.1778 1.3208)
			(layers "F.Cu" "F.Mask" "F.Paste")
			(net "P3V3_AUX_CPU0_USB_AVDD33")
		)
		(pad "5" smd rect
			(at -3.849878 -1.599946 270)
			(size 0.1778 1.3208)
			(layers "F.Cu" "F.Mask" "F.Paste")
			(net "USB3_CPU0_BMC_RX_HUB1_DN")
		)
		(pad "6" smd rect
			(at -3.849878 -1.199896 270)
			(size 0.1778 1.3208)
			(layers "F.Cu" "F.Mask" "F.Paste")
			(net "USB3_CPU0_BMC_RX_HUB1_DP")
		)
		(pad "7" smd rect
			(at -3.849878 -0.8001 270)
			(size 0.1778 1.3208)
			(layers "F.Cu" "F.Mask" "F.Paste")
			(net "P1V2_AUX")
		)
		(pad "8" smd rect
			(at -3.849878 -0.40005 270)
			(size 0.1778 1.3208)
			(layers "F.Cu" "F.Mask" "F.Paste")
			(net "USB3_CPU0_BMC_TX_C1_DN")
		)
		(pad "9" smd rect
			(at -3.849878 0 270)
			(size 0.1778 1.3208)
			(layers "F.Cu" "F.Mask" "F.Paste")
			(net "USB3_CPU0_BMC_TX_C1_DP")
		)
		(pad "10" smd rect
			(at -3.849878 0.40005 270)
			(size 0.1778 1.3208)
			(layers "F.Cu" "F.Mask" "F.Paste")
			(net "P1V2_AUX")
		)
		(pad "11" smd rect
			(at -3.849878 0.8001 270)
			(size 0.1778 1.3208)
			(layers "F.Cu" "F.Mask" "F.Paste")
			(net "Net_10799")
		)
		(pad "12" smd rect
			(at -3.849878 1.199896 270)
			(size 0.1778 1.3208)
			(layers "F.Cu" "F.Mask" "F.Paste")
			(net "Net_10800")
		)
		(pad "13" smd rect
			(at -3.849878 1.599946 270)
			(size 0.1778 1.3208)
			(layers "F.Cu" "F.Mask" "F.Paste")
			(net "P1V2_AUX")
		)
		(pad "14" smd rect
			(at -3.849878 1.999996 270)
			(size 0.1778 1.3208)
			(layers "F.Cu" "F.Mask" "F.Paste")
			(net "Net_10802")
		)
		(pad "15" smd rect
			(at -3.849878 2.400046 270)
			(size 0.1778 1.3208)
			(layers "F.Cu" "F.Mask" "F.Paste")
			(net "Net_10801")
		)
		(pad "16" smd rect
			(at -3.849878 2.800096 270)
			(size 0.1778 1.3208)
			(layers "F.Cu" "F.Mask" "F.Paste")
			(net "P1V2_AUX")
		)
		(pad "17" smd rect
			(at -3.999992 3.199892 270)
			(size 0.1778 1.016)
			(layers "F.Cu" "F.Mask" "F.Paste")
			(net "USB_CPU0_HUB1_VBUS_US")
		)
		(pad "18" smd rect
			(at -3.199892 3.999992 180)
			(size 0.1778 1.016)
			(layers "F.Cu" "F.Mask" "F.Paste")
			(net "USB_CPU0_HUB1_VBUS_DS")
		)
		(pad "19" smd rect
			(at -2.800096 3.849878 180)
			(size 0.1778 1.3208)
			(layers "F.Cu" "F.Mask" "F.Paste")
			(net "P1V2_CPU0_USB_DVDD12")
		)
		(pad "20" smd rect
			(at -2.400046 3.849878 180)
			(size 0.1778 1.3208)
			(layers "F.Cu" "F.Mask" "F.Paste")
			(net "TP_CPU0_USB_HUB1_SUSPEND")
		)
		(pad "21" smd rect
			(at -1.999996 3.849878 180)
			(size 0.1778 1.3208)
			(layers "F.Cu" "F.Mask" "F.Paste")
			(net "PU_CPU0_USB_HUB_RESERVED1")
		)
		(pad "22" smd rect
			(at -1.599946 3.849878 180)
			(size 0.1778 1.3208)
			(layers "F.Cu" "F.Mask" "F.Paste")
			(net "PU_CPU0_USB_HUB_RESERVED2")
		)
		(pad "23" smd rect
			(at -1.199896 3.849878 180)
			(size 0.1778 1.3208)
			(layers "F.Cu" "F.Mask" "F.Paste")
			(net "USB_CPU0_HUB1_MODE_SEL0")
		)
		(pad "24" smd rect
			(at -0.8001 3.849878 180)
			(size 0.1778 1.3208)
			(layers "F.Cu" "F.Mask" "F.Paste")
			(net "USB_CPU0_HUB1_MODE_SEL1")
		)
		(pad "25" smd rect
			(at -0.40005 3.849878 180)
			(size 0.1778 1.3208)
			(layers "F.Cu" "F.Mask" "F.Paste")
			(net "Net_10798")
		)
		(pad "26" smd rect
			(at 0 3.849878 180)
			(size 0.1778 1.3208)
			(layers "F.Cu" "F.Mask" "F.Paste")
			(net "USB_CPU0_HUB1_RREF_SS")
		)
		(pad "27" smd rect
			(at 0.40005 3.849878 180)
			(size 0.1778 1.3208)
			(layers "F.Cu" "F.Mask" "F.Paste")
			(net "P1V2_CPU0_USB_DVDD12")
		)
		(pad "28" smd rect
			(at 0.8001 3.849878 180)
			(size 0.1778 1.3208)
			(layers "F.Cu" "F.Mask" "F.Paste")
			(net "P3V3_AUX")
		)
		(pad "29" smd rect
			(at 1.199896 3.849878 180)
			(size 0.1778 1.3208)
			(layers "F.Cu" "F.Mask" "F.Paste")
			(net "PU_CPU0_USB_HUB_PWR_EN")
		)
		(pad "30" smd rect
			(at 1.599946 3.849878 180)
			(size 0.1778 1.3208)
			(layers "F.Cu" "F.Mask" "F.Paste")
			(net "PU_CPU0_USB_HUB_OVRCURR")
		)
		(pad "31" smd rect
			(at 1.999996 3.849878 180)
			(size 0.1778 1.3208)
			(layers "F.Cu" "F.Mask" "F.Paste")
			(net "RST_USB_CPU0_HUB1_R_N")
		)
		(pad "32" smd rect
			(at 2.400046 3.849878 180)
			(size 0.1778 1.3208)
			(layers "F.Cu" "F.Mask" "F.Paste")
			(net "SMB_USB_CPU0_HUB1_SCL")
		)
		(pad "33" smd rect
			(at 2.800096 3.849878 180)
			(size 0.1778 1.3208)
			(layers "F.Cu" "F.Mask" "F.Paste")
			(net "SMB_USB_CPU0_HUB1_SDA")
		)
		(pad "34" smd rect
			(at 3.199892 3.999992 180)
			(size 0.1778 1.016)
			(layers "F.Cu" "F.Mask" "F.Paste")
			(net "P1V2_AUX")
		)
		(pad "35" smd rect
			(at 3.999992 3.199892 270)
			(size 0.1778 1.016)
			(layers "F.Cu" "F.Mask" "F.Paste")
			(net "Net_10807")
		)
		(pad "36" smd rect
			(at 3.849878 2.800096 270)
			(size 0.1778 1.3208)
			(layers "F.Cu" "F.Mask" "F.Paste")
			(net "Net_10808")
		)
		(pad "37" smd rect
			(at 3.849878 2.400046 270)
			(size 0.1778 1.3208)
			(layers "F.Cu" "F.Mask" "F.Paste")
			(net "P1V2_AUX")
		)
		(pad "38" smd rect
			(at 3.849878 1.999996 270)
			(size 0.1778 1.3208)
			(layers "F.Cu" "F.Mask" "F.Paste")
			(net "Net_10805")
		)
		(pad "39" smd rect
			(at 3.849878 1.599946 270)
			(size 0.1778 1.3208)
			(layers "F.Cu" "F.Mask" "F.Paste")
			(net "Net_10806")
		)
		(pad "40" smd rect
			(at 3.849878 1.199896 270)
			(size 0.1778 1.3208)
			(layers "F.Cu" "F.Mask" "F.Paste")
			(net "GND")
		)
		(pad "41" smd rect
			(at 3.849878 0.8001 270)
			(size 0.1778 1.3208)
			(layers "F.Cu" "F.Mask" "F.Paste")
			(net "Net_10811")
		)
		(pad "42" smd rect
			(at 3.849878 0.40005 270)
			(size 0.1778 1.3208)
			(layers "F.Cu" "F.Mask" "F.Paste")
			(net "Net_10812")
		)
		(pad "43" smd rect
			(at 3.849878 0 270)
			(size 0.1778 1.3208)
			(layers "F.Cu" "F.Mask" "F.Paste")
			(net "P1V2_AUX")
		)
		(pad "44" smd rect
			(at 3.849878 -0.40005 270)
			(size 0.1778 1.3208)
			(layers "F.Cu" "F.Mask" "F.Paste")
			(net "Net_10814")
		)
		(pad "45" smd rect
			(at 3.849878 -0.8001 270)
			(size 0.1778 1.3208)
			(layers "F.Cu" "F.Mask" "F.Paste")
			(net "Net_10813")
		)
	)
)
